(kicad_pcb
	(version 20241229)
	(generator "pcbnew")
	(generator_version "9.0")
	(general
		(thickness 1.292)
		(legacy_teardrops no)
	)
	(paper "A4")
	(title_block
		(title "LPDDR5 Testbed")
		(date "2023-12-19")
		(rev "1.0.0")
		(comment 9 "footprints 150-154 of 160")
	)
	(layers
		(0 "F.Cu" signal)
		(4 "In1.Cu" power)
		(6 "In2.Cu" power)
		(8 "In3.Cu" signal)
		(10 "In4.Cu" signal)
		(2 "B.Cu" signal)
		(9 "F.Adhes" user "F.Adhesive")
		(11 "B.Adhes" user "B.Adhesive")
		(13 "F.Paste" user)
		(15 "B.Paste" user)
		(5 "F.SilkS" user "F.Silkscreen")
		(7 "B.SilkS" user "B.Silkscreen")
		(1 "F.Mask" user)
		(3 "B.Mask" user)
		(17 "Dwgs.User" user "User.Drawings")
		(19 "Cmts.User" user "User.Comments")
		(21 "Eco1.User" user "User.Eco1")
		(23 "Eco2.User" user "User.Eco2")
		(25 "Edge.Cuts" user)
		(27 "Margin" user)
		(31 "F.CrtYd" user "F.Courtyard")
		(29 "B.CrtYd" user "B.Courtyard")
		(35 "F.Fab" user)
		(33 "B.Fab" user)
	)
	(footprint "antmicro-footprints:R_Array_4x0402_Panasonic_EXB28V"
		(layer "B.Cu")
		(at 152.2 93.8)
		(property "Reference" "R77"
			(at -1.1 1.8 0)
			(unlocked yes)
			(layer "B.SilkS")
			(effects
				(font
					(size 0.7 0.7)
					(thickness 0.15)
				)
				(justify right bottom mirror)
			)
		)
		(property "Value" "R_4x100R_0402_array"
			(at -1.5 -2 0)
			(layer "B.Fab")
			(effects
				(font
					(size 0.7 0.7)
					(thickness 0.15)
				)
				(justify right bottom mirror)
			)
		)
		(property "Author" "Antmicro"
			(at 0 0 0)
			(layer "B.Fab")
			(hide yes)
			(effects
				(font
					(size 1 1)
					(thickness 0.15)
				)
				(justify mirror)
			)
		)
		(property "License" "Apache-2.0"
			(at 0 0 0)
			(layer "B.Fab")
			(hide yes)
			(effects
				(font
					(size 1 1)
					(thickness 0.15)
				)
				(justify mirror)
			)
		)
		(property "MPN" "EXB-28V101JX"
			(at 0 0 0)
			(layer "B.Fab")
			(hide yes)
			(effects
				(font
					(size 1 1)
					(thickness 0.15)
				)
				(justify mirror)
			)
		)
		(property "Manufacturer" "Panasonic"
			(at 0 0 0)
			(layer "B.Fab")
			(hide yes)
			(effects
				(font
					(size 1 1)
					(thickness 0.15)
				)
				(justify mirror)
			)
		)
		(property "Val" "R_4x100R_0402"
			(at 0 0 0)
			(layer "B.Fab")
			(hide yes)
			(effects
				(font
					(size 1 1)
					(thickness 0.15)
				)
				(justify mirror)
			)
		)
		(sheetname "Translators1")
		(sheetfile "translators.kicad_sch")
		(attr smd)
		(fp_line
			(start -1.25 0.5)
			(end -1.25 -0.498)
			(stroke
				(width 0.15)
				(type solid)
			)
			(layer "B.SilkS")
		)
		(fp_line
			(start 1.25 -0.499)
			(end 1.25 0.499)
			(stroke
				(width 0.15)
				(type solid)
			)
			(layer "B.SilkS")
		)
		(fp_rect
			(start -1.25 0.8)
			(end 1.25 -0.8)
			(stroke
				(width 0.05)
				(type solid)
			)
			(fill no)
			(layer "B.CrtYd")
		)
		(fp_line
			(start -1 -0.498)
			(end -1 0.5)
			(stroke
				(width 0.15)
				(type solid)
			)
			(layer "B.Fab")
		)
		(fp_line
			(start -1 0.5)
			(end 0.998 0.5)
			(stroke
				(width 0.15)
				(type solid)
			)
			(layer "B.Fab")
		)
		(fp_line
			(start 0.998 -0.498)
			(end -1 -0.498)
			(stroke
				(width 0.15)
				(type solid)
			)
			(layer "B.Fab")
		)
		(fp_line
			(start 0.998 0.5)
			(end 0.998 -0.498)
			(stroke
				(width 0.15)
				(type solid)
			)
			(layer "B.Fab")
		)
		(pad "1" smd roundrect
			(at -0.8875 -0.45)
			(size 0.525 0.5)
			(layers "B.Cu" "B.Mask" "B.Paste")
			(roundrect_rratio 0.25)
			(net 206 "/LPDDR5/LPDDR5_B.DQ8")
			(pinfunction "R1.1")
			(pintype "passive")
		)
		(pad "2" smd roundrect
			(at -0.25 -0.45)
			(size 0.25 0.5)
			(layers "B.Cu" "B.Mask" "B.Paste")
			(roundrect_rratio 0.25)
			(net 208 "/LPDDR5/LPDDR5_B.DQ10")
			(pinfunction "R2.1")
			(pintype "passive")
		)
		(pad "3" smd roundrect
			(at 0.25 -0.45)
			(size 0.25 0.5)
			(layers "B.Cu" "B.Mask" "B.Paste")
			(roundrect_rratio 0.25)
			(net 207 "/LPDDR5/LPDDR5_B.DQ9")
			(pinfunction "R3.1")
			(pintype "passive")
		)
		(pad "4" smd roundrect
			(at 0.8875 -0.45)
			(size 0.525 0.5)
			(layers "B.Cu" "B.Mask" "B.Paste")
			(roundrect_rratio 0.25)
			(net 209 "/LPDDR5/LPDDR5_B.DQ11")
			(pinfunction "R4.1")
			(pintype "passive")
		)
		(pad "5" smd roundrect
			(at 0.8875 0.45)
			(size 0.525 0.5)
			(layers "B.Cu" "B.Mask" "B.Paste")
			(roundrect_rratio 0.25)
			(net 14 "GND")
			(pinfunction "R4.2")
			(pintype "passive")
		)
		(pad "6" smd roundrect
			(at 0.25 0.45)
			(size 0.25 0.5)
			(layers "B.Cu" "B.Mask" "B.Paste")
			(roundrect_rratio 0.25)
			(net 14 "GND")
			(pinfunction "R3.2")
			(pintype "passive")
		)
		(pad "7" smd roundrect
			(at -0.25 0.45)
			(size 0.25 0.5)
			(layers "B.Cu" "B.Mask" "B.Paste")
			(roundrect_rratio 0.25)
			(net 14 "GND")
			(pinfunction "R2.2")
			(pintype "passive")
		)
		(pad "8" smd roundrect
			(at -0.8875 0.45)
			(size 0.525 0.5)
			(layers "B.Cu" "B.Mask" "B.Paste")
			(roundrect_rratio 0.25)
			(net 14 "GND")
			(pinfunction "R1.2")
			(pintype "passive")
		)
	)
	(footprint "antmicro-footprints:R_0402_1005Metric"
		(layer "B.Cu")
		(at 135.15 91.35 -90)
		(descr "Resistor SMD 0402")
		(tags "resistor SMD 0402")
		(property "Reference" "R55"
			(at -1.122484 0.772697 90)
			(unlocked yes)
			(layer "B.SilkS")
			(effects
				(font
					(size 0.7 0.7)
					(thickness 0.15)
				)
				(justify left bottom mirror)
			)
		)
		(property "Value" "R_100R_0402"
			(at -1.011843 -1.772047 90)
			(layer "B.Fab")
			(effects
				(font
					(size 0.7 0.7)
					(thickness 0.15)
				)
				(justify left bottom mirror)
			)
		)
		(property "Author" "Antmicro"
			(at 43.8 226.5 0)
			(layer "B.Fab")
			(hide yes)
			(effects
				(font
					(size 1 1)
					(thickness 0.15)
				)
				(justify mirror)
			)
		)
		(property "License" "Apache-2.0"
			(at 43.8 226.5 0)
			(layer "B.Fab")
			(hide yes)
			(effects
				(font
					(size 1 1)
					(thickness 0.15)
				)
				(justify mirror)
			)
		)
		(property "MPN" "CR0402-FX-1000GLF"
			(at 43.8 226.5 0)
			(layer "B.Fab")
			(hide yes)
			(effects
				(font
					(size 1 1)
					(thickness 0.15)
				)
				(justify mirror)
			)
		)
		(property "Manufacturer" "Bourns"
			(at 43.8 226.5 0)
			(layer "B.Fab")
			(hide yes)
			(effects
				(font
					(size 1 1)
					(thickness 0.15)
				)
				(justify mirror)
			)
		)
		(property "Tolerance" "1%"
			(at 43.8 226.5 0)
			(layer "B.Fab")
			(hide yes)
			(effects
				(font
					(size 1 1)
					(thickness 0.15)
				)
				(justify mirror)
			)
		)
		(property "Val" "100R"
			(at 43.8 226.5 0)
			(layer "B.Fab")
			(hide yes)
			(effects
				(font
					(size 1 1)
					(thickness 0.15)
				)
				(justify mirror)
			)
		)
		(sheetname "Translators")
		(sheetfile "translators.kicad_sch")
		(attr smd)
		(fp_rect
			(start -0.93 0.47)
			(end 0.93 -0.47)
			(stroke
				(width 0.05)
				(type solid)
			)
			(fill no)
			(layer "B.CrtYd")
		)
		(fp_rect
			(start -0.5 0.25)
			(end 0.5 -0.25)
			(stroke
				(width 0.15)
				(type solid)
			)
			(fill no)
			(layer "B.Fab")
		)
		(pad "1" smd roundrect
			(at -0.485 0 270)
			(size 0.59 0.64)
			(layers "B.Cu" "B.Mask" "B.Paste")
			(roundrect_rratio 0.25)
			(net 49 "/LPDDR5/LPDDR5_A.CK_P")
			(pintype "passive")
		)
		(pad "2" smd roundrect
			(at 0.485 0 270)
			(size 0.59 0.64)
			(layers "B.Cu" "B.Mask" "B.Paste")
			(roundrect_rratio 0.25)
			(net 14 "GND")
			(pintype "passive")
		)
	)
	(footprint "antmicro-footprints:Conn_JST_SH_1x4_SM04B-SRSS-TB-LF-SN"
		(layer "B.Cu")
		(at 118.975 62.95)
		(property "Reference" "J3"
			(at -3.475 3.25 0)
			(unlocked yes)
			(layer "B.SilkS")
			(effects
				(font
					(size 0.7 0.7)
					(thickness 0.15)
				)
				(justify right bottom mirror)
			)
		)
		(property "Value" "JST_SH_1x4_SM04B-SRSS-TB-LF-SN"
			(at 0 -3.9 0)
			(layer "B.Fab")
			(effects
				(font
					(size 0.7 0.7)
					(thickness 0.15)
				)
				(justify right bottom mirror)
			)
		)
		(property "Author" "Antmicro"
			(at 0 0 0)
			(layer "B.Fab")
			(hide yes)
			(effects
				(font
					(size 1 1)
					(thickness 0.15)
				)
				(justify mirror)
			)
		)
		(property "License" "Apache-2.0"
			(at 0 0 0)
			(layer "B.Fab")
			(hide yes)
			(effects
				(font
					(size 1 1)
					(thickness 0.15)
				)
				(justify mirror)
			)
		)
		(property "MPN" "SM04B-SRSS-TB(LF)(SN)"
			(at 0 0 0)
			(layer "B.Fab")
			(hide yes)
			(effects
				(font
					(size 1 1)
					(thickness 0.15)
				)
				(justify mirror)
			)
		)
		(property "Manufacturer" "JST Automotive Connectors"
			(at 0 0 0)
			(layer "B.Fab")
			(hide yes)
			(effects
				(font
					(size 1 1)
					(thickness 0.15)
				)
				(justify mirror)
			)
		)
		(sheetname "Power supply")
		(sheetfile "power_supply.kicad_sch")
		(attr smd)
		(fp_line
			(start -3.2 1.9)
			(end -3.2 -0.2)
			(stroke
				(width 0.15)
				(type solid)
			)
			(layer "B.SilkS")
		)
		(fp_line
			(start -2.1 1.9)
			(end -3.2 1.9)
			(stroke
				(width 0.15)
				(type solid)
			)
			(layer "B.SilkS")
		)
		(fp_line
			(start -2 -2.101)
			(end 1.999 -2.101)
			(stroke
				(width 0.15)
				(type solid)
			)
			(layer "B.SilkS")
		)
		(fp_line
			(start 2 1.9)
			(end 3.2 1.9)
			(stroke
				(width 0.15)
				(type solid)
			)
			(layer "B.SilkS")
		)
		(fp_line
			(start 3.2 1.9)
			(end 3.2 -0.2)
			(stroke
				(width 0.15)
				(type solid)
			)
			(layer "B.SilkS")
		)
		(fp_circle
			(center -2 2.2)
			(end -1.95 2.15)
			(stroke
				(width 0.15)
				(type solid)
			)
			(fill yes)
			(layer "B.SilkS")
		)
		(fp_line
			(start -3.6 -2.75)
			(end -3.6 2.2)
			(stroke
				(width 0.05)
				(type solid)
			)
			(layer "B.CrtYd")
		)
		(fp_line
			(start -3.6 2.2)
			(end -2.1 2.2)
			(stroke
				(width 0.05)
				(type solid)
			)
			(layer "B.CrtYd")
		)
		(fp_line
			(start -2.1 2.2)
			(end -2.1 3.45)
			(stroke
				(width 0.05)
				(type solid)
			)
			(layer "B.CrtYd")
		)
		(fp_line
			(start -2.1 3.45)
			(end 2.1 3.45)
			(stroke
				(width 0.05)
				(type solid)
			)
			(layer "B.CrtYd")
		)
		(fp_line
			(start 2.1 2.2)
			(end 3.6 2.2)
			(stroke
				(width 0.05)
				(type solid)
			)
			(layer "B.CrtYd")
		)
		(fp_line
			(start 2.1 3.45)
			(end 2.1 2.2)
			(stroke
				(width 0.05)
				(type solid)
			)
			(layer "B.CrtYd")
		)
		(fp_line
			(start 3.6 -2.75)
			(end -3.6 -2.75)
			(stroke
				(width 0.05)
				(type solid)
			)
			(layer "B.CrtYd")
		)
		(fp_line
			(start 3.6 2.2)
			(end 3.6 -2.75)
			(stroke
				(width 0.05)
				(type solid)
			)
			(layer "B.CrtYd")
		)
		(fp_line
			(start -3.5 -2.125)
			(end -3.5 2.125)
			(stroke
				(width 0.15)
				(type solid)
			)
			(layer "B.Fab")
		)
		(fp_line
			(start -3.5 -2.125)
			(end 3.499 -2.125)
			(stroke
				(width 0.15)
				(type solid)
			)
			(layer "B.Fab")
		)
		(fp_line
			(start 3.499 2.125)
			(end -3.5 2.125)
			(stroke
				(width 0.15)
				(type solid)
			)
			(layer "B.Fab")
		)
		(fp_line
			(start 3.499 2.125)
			(end 3.499 -2.125)
			(stroke
				(width 0.15)
				(type solid)
			)
			(layer "B.Fab")
		)
		(pad "1" smd roundrect
			(at -1.5 2.45 180)
			(size 0.6 1.55)
			(layers "B.Cu" "B.Mask" "B.Paste")
			(roundrect_rratio 0.25)
			(net 14 "GND")
			(pinfunction "1")
			(pintype "passive")
		)
		(pad "2" smd roundrect
			(at -0.5 2.45 180)
			(size 0.6 1.55)
			(layers "B.Cu" "B.Mask" "B.Paste")
			(roundrect_rratio 0.25)
			(net 15 "/Power supply/3.3V_QWIIC")
			(pinfunction "2")
			(pintype "passive")
		)
		(pad "3" smd roundrect
			(at 0.498 2.45 180)
			(size 0.6 1.55)
			(layers "B.Cu" "B.Mask" "B.Paste")
			(roundrect_rratio 0.25)
			(net 38 "/Power supply/I2C.SDA")
			(pinfunction "3")
			(pintype "passive")
		)
		(pad "4" smd roundrect
			(at 1.499 2.45 180)
			(size 0.6 1.55)
			(layers "B.Cu" "B.Mask" "B.Paste")
			(roundrect_rratio 0.25)
			(net 39 "/Power supply/I2C.SCL")
			(pinfunction "4")
			(pintype "passive")
		)
		(pad "SH1" smd roundrect
			(at -2.801 -1.426)
			(size 1.2 1.8)
			(layers "B.Cu" "B.Mask" "B.Paste")
			(roundrect_rratio 0.05)
			(net 14 "GND")
			(pinfunction "SH1")
			(pintype "passive")
		)
		(pad "SH2" smd roundrect
			(at 2.798 -1.426)
			(size 1.2 1.8)
			(layers "B.Cu" "B.Mask" "B.Paste")
			(roundrect_rratio 0.05)
			(net 14 "GND")
			(pinfunction "SH2")
			(pintype "passive")
		)
	)
	(footprint "antmicro-footprints:C_0402_1005Metric"
		(layer "B.Cu")
		(at 137.575 75.55 90)
		(descr "Capacitor SMD 0402")
		(tags "capacitor SMD 0402")
		(property "Reference" "C45"
			(at 1.35 0.025 90)
			(unlocked yes)
			(layer "B.SilkS")
			(effects
				(font
					(size 0.7 0.7)
					(thickness 0.15)
				)
				(justify right bottom mirror)
			)
		)
		(property "Value" "C_4u7_0402"
			(at -1.022927 -2.155213 90)
			(layer "B.Fab")
			(effects
				(font
					(size 0.7 0.7)
					(thickness 0.15)
				)
				(justify right bottom mirror)
			)
		)
		(property "Author" "Antmicro"
			(at 213.125 -62.025 0)
			(layer "B.Fab")
			(hide yes)
			(effects
				(font
					(size 1 1)
					(thickness 0.15)
				)
				(justify mirror)
			)
		)
		(property "Dielectric" ""
			(at 213.125 -62.025 0)
			(layer "B.Fab")
			(hide yes)
			(effects
				(font
					(size 1 1)
					(thickness 0.15)
				)
				(justify mirror)
			)
		)
		(property "License" "Apache-2.0"
			(at 213.125 -62.025 0)
			(layer "B.Fab")
			(hide yes)
			(effects
				(font
					(size 1 1)
					(thickness 0.15)
				)
				(justify mirror)
			)
		)
		(property "MPN" "GRM155R61A475MEAAD"
			(at 213.125 -62.025 0)
			(layer "B.Fab")
			(hide yes)
			(effects
				(font
					(size 1 1)
					(thickness 0.15)
				)
				(justify mirror)
			)
		)
		(property "Manufacturer" "Murata"
			(at 213.125 -62.025 0)
			(layer "B.Fab")
			(hide yes)
			(effects
				(font
					(size 1 1)
					(thickness 0.15)
				)
				(justify mirror)
			)
		)
		(property "Val" "4u7"
			(at 213.125 -62.025 0)
			(layer "B.Fab")
			(hide yes)
			(effects
				(font
					(size 1 1)
					(thickness 0.15)
				)
				(justify mirror)
			)
		)
		(property "Voltage" ""
			(at 213.125 -62.025 0)
			(layer "B.Fab")
			(hide yes)
			(effects
				(font
					(size 1 1)
					(thickness 0.15)
				)
				(justify mirror)
			)
		)
		(sheetname "LPDDR5")
		(sheetfile "lpddr5.kicad_sch")
		(attr smd)
		(fp_rect
			(start -0.9659 0.481258)
			(end 0.9649 -0.458742)
			(stroke
				(width 0.05)
				(type solid)
			)
			(fill no)
			(layer "B.CrtYd")
		)
		(fp_line
			(start 0.499 -0.248)
			(end -0.499 -0.248)
			(stroke
				(width 0.15)
				(type solid)
			)
			(layer "B.Fab")
		)
		(fp_line
			(start -0.499 -0.248)
			(end -0.499 0.25)
			(stroke
				(width 0.15)
				(type solid)
			)
			(layer "B.Fab")
		)
		(fp_line
			(start 0.499 0.25)
			(end 0.499 -0.248)
			(stroke
				(width 0.15)
				(type solid)
			)
			(layer "B.Fab")
		)
		(fp_line
			(start -0.499 0.25)
			(end 0.499 0.25)
			(stroke
				(width 0.15)
				(type solid)
			)
			(layer "B.Fab")
		)
		(pad "1" smd roundrect
			(at -0.484 0 90)
			(size 0.59 0.64)
			(layers "B.Cu" "B.Mask" "B.Paste")
			(roundrect_rratio 0.25)
			(net 14 "GND")
			(pintype "passive")
		)
		(pad "2" smd roundrect
			(at 0.484 0 90)
			(size 0.59 0.64)
			(layers "B.Cu" "B.Mask" "B.Paste")
			(roundrect_rratio 0.25)
			(net 4 "+0V5")
			(pintype "passive")
		)
	)
	(footprint "antmicro-footprints:R_0402_1005Metric"
		(layer "B.Cu")
		(at 152.985 89.31 180)
		(descr "Resistor SMD 0402")
		(tags "resistor SMD 0402")
		(property "Reference" "R81"
			(at -1.015 0.61 0)
			(unlocked yes)
			(layer "B.SilkS")
			(effects
				(font
					(size 0.7 0.7)
					(thickness 0.15)
				)
				(justify left bottom mirror)
			)
		)
		(property "Value" "R_100R_0402"
			(at -1.011843 -1.772047 0)
			(layer "B.Fab")
			(effects
				(font
					(size 0.7 0.7)
					(thickness 0.15)
				)
				(justify left bottom mirror)
			)
		)
		(property "Author" "Antmicro"
			(at 305.97 178.62 0)
			(layer "B.Fab")
			(hide yes)
			(effects
				(font
					(size 1 1)
					(thickness 0.15)
				)
				(justify mirror)
			)
		)
		(property "License" "Apache-2.0"
			(at 305.97 178.62 0)
			(layer "B.Fab")
			(hide yes)
			(effects
				(font
					(size 1 1)
					(thickness 0.15)
				)
				(justify mirror)
			)
		)
		(property "MPN" "CR0402-FX-1000GLF"
			(at 305.97 178.62 0)
			(layer "B.Fab")
			(hide yes)
			(effects
				(font
					(size 1 1)
					(thickness 0.15)
				)
				(justify mirror)
			)
		)
		(property "Manufacturer" "Bourns"
			(at 305.97 178.62 0)
			(layer "B.Fab")
			(hide yes)
			(effects
				(font
					(size 1 1)
					(thickness 0.15)
				)
				(justify mirror)
			)
		)
		(property "Tolerance" "1%"
			(at 305.97 178.62 0)
			(layer "B.Fab")
			(hide yes)
			(effects
				(font
					(size 1 1)
					(thickness 0.15)
				)
				(justify mirror)
			)
		)
		(property "Val" "100R"
			(at 305.97 178.62 0)
			(layer "B.Fab")
			(hide yes)
			(effects
				(font
					(size 1 1)
					(thickness 0.15)
				)
				(justify mirror)
			)
		)
		(sheetname "Translators1")
		(sheetfile "translators.kicad_sch")
		(attr smd)
		(fp_rect
			(start -0.93 0.47)
			(end 0.93 -0.47)
			(stroke
				(width 0.05)
				(type solid)
			)
			(fill no)
			(layer "B.CrtYd")
		)
		(fp_rect
			(start -0.5 0.25)
			(end 0.5 -0.25)
			(stroke
				(width 0.15)
				(type solid)
			)
			(fill no)
			(layer "B.Fab")
		)
		(pad "1" smd roundrect
			(at -0.485 0 180)
			(size 0.59 0.64)
			(layers "B.Cu" "B.Mask" "B.Paste")
			(roundrect_rratio 0.25)
			(net 110 "/LPDDR5/LPDDR5_B.WCK1_N")
			(pintype "passive")
		)
		(pad "2" smd roundrect
			(at 0.485 0 180)
			(size 0.59 0.64)
			(layers "B.Cu" "B.Mask" "B.Paste")
			(roundrect_rratio 0.25)
			(net 14 "GND")
			(pintype "passive")
		)
	)
)
